# S9S_MB_2U (Grand Teton) — schematic netlist excerpt (pin names and nets, part order shuffled) for the footprints in the layout excerpt that follows; sources: Cadence DE-HDL packaged netlist, KiCad conversion of 03242023_DA0F0TMBIJ0_F0T_Motherboard_J_brd_V01_OCP.brd

R918  Q_RES  0 5% CHIP  pkg 0402LF  page 185 : A = SPI_PCH_IO2 ; B = SPI_SYS_WP_IO2
C1283  Q_CAP  0.1UF 25V 10% X7R  pkg 0402  page 191 : A = P3V3_E1S_0 ; B = GND
C40  Q_CAP  10UF 16V 10% X6S  pkg C0805  page 94 : A = P12V_S3_AUX_CPU0_NVDIMM ; B = GND

(kicad_pcb
	(version 20260206)
	(generator "pcbnew")
	(generator_version "10.0")
	(general
		(thickness 1.6)
		(legacy_teardrops no)
	)
	(paper "A4")
	(title_block
		(title "03242023_DA0F0TMBIJ0_F0T_Motherboard_J_brd_V01_OCP.brd")
		(comment 1 "Grand Teton / footprints 5691-5693 of 6105")
	)
	(layers
		(0 "F.Cu" signal "TOP")
		(4 "In1.Cu" signal "GND")
		(6 "In2.Cu" signal "IN1")
		(8 "In3.Cu" signal "GND1")
		(10 "In4.Cu" signal "IN2")
		(12 "In5.Cu" signal "GND2")
		(14 "In6.Cu" signal "IN3")
		(16 "In7.Cu" signal "GND3")
		(18 "In8.Cu" signal "VCC")
		(20 "In9.Cu" signal "VCC1")
		(22 "In10.Cu" signal "GND4")
		(24 "In11.Cu" signal "IN4")
		(26 "In12.Cu" signal "GND5")
		(28 "In13.Cu" signal "IN5")
		(30 "In14.Cu" signal "GND6")
		(32 "In15.Cu" signal "IN6")
		(34 "In16.Cu" signal "GND7")
		(2 "B.Cu" signal "BOTTOM")
		(9 "F.Adhes" user "F.Adhesive")
		(11 "B.Adhes" user "B.Adhesive")
		(13 "F.Paste" user "Package Geometry/Pastemask Top")
		(15 "B.Paste" user "Package Geometry/Pastemask Bottom")
		(5 "F.SilkS" user "Ref Des/Silkscreen Top")
		(7 "B.SilkS" user "Ref Des/Silkscreen Bottom")
		(1 "F.Mask" user "Board Geometry/Soldermask Top")
		(3 "B.Mask" user "Board Geometry/Soldermask Bottom")
		(17 "Dwgs.User" user "User.Drawings")
		(19 "Cmts.User" user "User.Comments")
		(21 "Eco1.User" user "User.Eco1")
		(23 "Eco2.User" user "User.Eco2")
		(25 "Edge.Cuts" user "Board Geometry/Outline")
		(27 "Margin" user)
		(31 "F.CrtYd" user "Package Geometry/Place Bound Top")
		(29 "B.CrtYd" user "Package Geometry/Place Bound Bottom")
		(35 "F.Fab" user "Ref Des/Assembly Top")
		(33 "B.Fab" user "Ref Des/Assembly Bottom")
	)
	(footprint ""
		(layer "B.Cu")
		(at 236.62513 -48.104044)
		(property "Reference" "C1283"
			(at 0 0 0)
			(layer "B.SilkS")
			(hide yes)
			(effects
				(font
					(size 1.27 1.27)
				)
				(justify mirror)
			)
		)
		(property "Value" ""
			(at 0 0 0)
			(layer "B.Fab")
			(effects
				(font
					(size 1.27 1.27)
				)
				(justify mirror)
			)
		)
		(duplicate_pad_numbers_are_jumpers no)
		(fp_line
			(start -0.7874 -0.4064)
			(end -0.7874 0.4064)
			(stroke
				(width 0.1524)
				(type default)
			)
			(layer "B.SilkS")
		)
		(fp_line
			(start -0.7874 0.4064)
			(end 0.7874 0.4064)
			(stroke
				(width 0.1524)
				(type default)
			)
			(layer "B.SilkS")
		)
		(fp_line
			(start 0.7874 -0.4064)
			(end -0.7874 -0.4064)
			(stroke
				(width 0.1524)
				(type default)
			)
			(layer "B.SilkS")
		)
		(fp_line
			(start 0.7874 0.4064)
			(end 0.7874 -0.4064)
			(stroke
				(width 0.1524)
				(type default)
			)
			(layer "B.SilkS")
		)
		(fp_line
			(start -0.67945 -0.3048)
			(end -0.67945 0.3048)
			(stroke
				(width 0.1)
				(type default)
			)
			(layer "B.Fab")
		)
		(fp_line
			(start -0.67945 0.3048)
			(end -0.120396 0.3048)
			(stroke
				(width 0.1)
				(type default)
			)
			(layer "B.Fab")
		)
		(fp_line
			(start -0.12065 -0.3048)
			(end -0.67945 -0.3048)
			(stroke
				(width 0.1)
				(type default)
			)
			(layer "B.Fab")
		)
		(fp_line
			(start -0.12065 -0.2794)
			(end -0.12065 -0.3048)
			(stroke
				(width 0.1)
				(type default)
			)
			(layer "B.Fab")
		)
		(fp_line
			(start -0.120396 0.2794)
			(end 0.12065 0.2794)
			(stroke
				(width 0.1)
				(type default)
			)
			(layer "B.Fab")
		)
		(fp_line
			(start -0.120396 0.3048)
			(end -0.120396 0.2794)
			(stroke
				(width 0.1)
				(type default)
			)
			(layer "B.Fab")
		)
		(fp_line
			(start 0.12065 -0.305054)
			(end 0.12065 -0.2794)
			(stroke
				(width 0.1)
				(type default)
			)
			(layer "B.Fab")
		)
		(fp_line
			(start 0.12065 -0.2794)
			(end -0.12065 -0.2794)
			(stroke
				(width 0.1)
				(type default)
			)
			(layer "B.Fab")
		)
		(fp_line
			(start 0.12065 0.2794)
			(end 0.12065 0.3048)
			(stroke
				(width 0.1)
				(type default)
			)
			(layer "B.Fab")
		)
		(fp_line
			(start 0.12065 0.3048)
			(end 0.67945 0.3048)
			(stroke
				(width 0.1)
				(type default)
			)
			(layer "B.Fab")
		)
		(fp_line
			(start 0.67945 -0.305054)
			(end 0.12065 -0.305054)
			(stroke
				(width 0.1)
				(type default)
			)
			(layer "B.Fab")
		)
		(fp_line
			(start 0.67945 0.3048)
			(end 0.67945 -0.305054)
			(stroke
				(width 0.1)
				(type default)
			)
			(layer "B.Fab")
		)
		(pad "1" smd circle
			(at 0.40005 0 180)
			(size 0 0)
			(layers "B.Cu" "B.Mask" "B.Paste")
			(net "P3V3_E1S_0")
		)
		(pad "2" smd circle
			(at -0.40005 0 180)
			(size 0 0)
			(layers "B.Cu" "B.Mask" "B.Paste")
			(net "GND")
		)
	)
	(footprint ""
		(layer "B.Cu")
		(at 334.744314 -33.173162 90)
		(property "Reference" "R918"
			(at 0 0 90)
			(layer "B.SilkS")
			(hide yes)
			(effects
				(font
					(size 1.27 1.27)
				)
				(justify mirror)
			)
		)
		(property "Value" ""
			(at 0 0 90)
			(layer "B.Fab")
			(effects
				(font
					(size 1.27 1.27)
				)
				(justify mirror)
			)
		)
		(duplicate_pad_numbers_are_jumpers no)
		(fp_line
			(start 0.7874 -0.4064)
			(end -0.7874 -0.4064)
			(stroke
				(width 0.1524)
				(type default)
			)
			(layer "B.SilkS")
		)
		(fp_line
			(start -0.7874 -0.4064)
			(end -0.7874 0.4064)
			(stroke
				(width 0.1524)
				(type default)
			)
			(layer "B.SilkS")
		)
		(fp_line
			(start 0.7874 0.4064)
			(end 0.7874 -0.4064)
			(stroke
				(width 0.1524)
				(type default)
			)
			(layer "B.SilkS")
		)
		(fp_line
			(start -0.7874 0.4064)
			(end 0.7874 0.4064)
			(stroke
				(width 0.1524)
				(type default)
			)
			(layer "B.SilkS")
		)
		(fp_line
			(start 0.67945 -0.305054)
			(end 0.12065 -0.305054)
			(stroke
				(width 0.1)
				(type default)
			)
			(layer "B.Fab")
		)
		(fp_line
			(start 0.12065 -0.305054)
			(end 0.12065 -0.2794)
			(stroke
				(width 0.1)
				(type default)
			)
			(layer "B.Fab")
		)
		(fp_line
			(start -0.12065 -0.3048)
			(end -0.67945 -0.3048)
			(stroke
				(width 0.1)
				(type default)
			)
			(layer "B.Fab")
		)
		(fp_line
			(start -0.67945 -0.3048)
			(end -0.67945 0.3048)
			(stroke
				(width 0.1)
				(type default)
			)
			(layer "B.Fab")
		)
		(fp_line
			(start 0.12065 -0.2794)
			(end -0.12065 -0.2794)
			(stroke
				(width 0.1)
				(type default)
			)
			(layer "B.Fab")
		)
		(fp_line
			(start -0.12065 -0.2794)
			(end -0.12065 -0.3048)
			(stroke
				(width 0.1)
				(type default)
			)
			(layer "B.Fab")
		)
		(fp_line
			(start 0.12065 0.2794)
			(end 0.12065 0.3048)
			(stroke
				(width 0.1)
				(type default)
			)
			(layer "B.Fab")
		)
		(fp_line
			(start -0.120396 0.2794)
			(end 0.12065 0.2794)
			(stroke
				(width 0.1)
				(type default)
			)
			(layer "B.Fab")
		)
		(fp_line
			(start 0.67945 0.3048)
			(end 0.67945 -0.305054)
			(stroke
				(width 0.1)
				(type default)
			)
			(layer "B.Fab")
		)
		(fp_line
			(start 0.12065 0.3048)
			(end 0.67945 0.3048)
			(stroke
				(width 0.1)
				(type default)
			)
			(layer "B.Fab")
		)
		(fp_line
			(start -0.120396 0.3048)
			(end -0.120396 0.2794)
			(stroke
				(width 0.1)
				(type default)
			)
			(layer "B.Fab")
		)
		(fp_line
			(start -0.67945 0.3048)
			(end -0.120396 0.3048)
			(stroke
				(width 0.1)
				(type default)
			)
			(layer "B.Fab")
		)
		(pad "1" smd circle
			(at 0.40005 0 270)
			(size 0 0)
			(layers "B.Cu" "B.Mask" "B.Paste")
			(net "SPI_PCH_IO2")
		)
		(pad "2" smd circle
			(at -0.40005 0 270)
			(size 0 0)
			(layers "B.Cu" "B.Mask" "B.Paste")
			(net "SPI_SYS_WP_IO2")
		)
	)
	(footprint ""
		(layer "B.Cu")
		(at 444.485014 -321.549776 -90)
		(property "Reference" "C40"
			(at 0 0 90)
			(layer "B.SilkS")
			(hide yes)
			(effects
				(font
					(size 1.27 1.27)
				)
				(justify mirror)
			)
		)
		(property "Value" ""
			(at 0 0 90)
			(layer "B.Fab")
			(effects
				(font
					(size 1.27 1.27)
				)
				(justify mirror)
			)
		)
		(duplicate_pad_numbers_are_jumpers no)
		(fp_line
			(start -1.524 0.762)
			(end 1.524 0.762)
			(stroke
				(width 0.1524)
				(type default)
			)
			(layer "B.SilkS")
		)
		(fp_line
			(start 1.524 0.762)
			(end 1.524 -0.762)
			(stroke
				(width 0.1524)
				(type default)
			)
			(layer "B.SilkS")
		)
		(fp_line
			(start -1.524 -0.762)
			(end -1.524 0.762)
			(stroke
				(width 0.1524)
				(type default)
			)
			(layer "B.SilkS")
		)
		(fp_line
			(start 1.524 -0.762)
			(end -1.524 -0.762)
			(stroke
				(width 0.1524)
				(type default)
			)
			(layer "B.SilkS")
		)
		(fp_line
			(start -1.1049 0.724916)
			(end -1.1049 -0.724916)
			(stroke
				(width 0.1)
				(type default)
			)
			(layer "B.Fab")
		)
		(fp_line
			(start 1.1049 0.724916)
			(end -1.1049 0.724916)
			(stroke
				(width 0.1)
				(type default)
			)
			(layer "B.Fab")
		)
		(fp_line
			(start -1.1049 -0.724916)
			(end 1.1049 -0.724916)
			(stroke
				(width 0.1)
				(type default)
			)
			(layer "B.Fab")
		)
		(fp_line
			(start 1.1049 -0.724916)
			(end 1.1049 0.724916)
			(stroke
				(width 0.1)
				(type default)
			)
			(layer "B.Fab")
		)
		(pad "1" smd rect
			(at 0.889 0 270)
			(size 1.016 1.27)
			(layers "B.Cu" "B.Mask" "B.Paste")
			(net "P12V_S3_AUX_CPU0_NVDIMM")
		)
		(pad "2" smd rect
			(at -0.889 0 270)
			(size 1.016 1.27)
			(layers "B.Cu" "B.Mask" "B.Paste")
			(net "GND")
		)
	)
)
